#ISCELL
  mstr_symbols intel_corp_bpage *
  *
#ISCELL
  mstr_standard tap *
  page244_i1
#ISCELL
  mstr_standard offpage *
  page244_i10
#ISCELL
  mstr_standard tap *
  page244_i100
#ISCELL
  mstr_standard tap *
  page244_i101
#ISCELL
  mstr_standard tap *
  page244_i102
#CELL
  mstr_discrete res *
  page244_i103
#ISCELL
  mstr_standard offpage *
  page244_i104
#ISCELL
  mstr_standard tap *
  page244_i11
#CELL
  mstr_discrete cap *
  page244_i12
#ISCELL
  mstr_standard tap *
  page244_i13
#ISCELL
  mstr_standard tap *
  page244_i14
#ISCELL
  mstr_standard tap *
  page244_i15
#ISCELL
  mstr_standard tap *
  page244_i16
#CELL
  mstr_discrete cap *
  page244_i17
#ISCELL
  mstr_standard tap *
  page244_i18
#ISCELL
  mstr_standard tap *
  page244_i19
#CELL
  mstr_discrete cap *
  page244_i2
#ISCELL
  mstr_standard tap *
  page244_i20
#ISCELL
  mstr_standard tap *
  page244_i21
#ISCELL
  mstr_standard tap *
  page244_i22
#CELL
  mstr_discrete cap *
  page244_i23
#CELL
  mstr_discrete cap *
  page244_i24
#ISCELL
  mstr_standard tap *
  page244_i25
#ISCELL
  mstr_standard tap *
  page244_i26
#ISCELL
  mstr_standard tap *
  page244_i27
#CELL
  mstr_discrete cap *
  page244_i28
#CELL
  mstr_discrete cap *
  page244_i29
#ISCELL
  mstr_standard tap *
  page244_i3
#CELL
  mstr_discrete cap *
  page244_i30
#ISCELL
  mstr_standard tap *
  page244_i31
#ISCELL
  mstr_standard tap *
  page244_i32
#ISCELL
  mstr_standard tap *
  page244_i33
#ISCELL
  mstr_standard tap *
  page244_i34
#CELL
  mstr_discrete cap *
  page244_i35
#ISCELL
  mstr_standard tap *
  page244_i36
#ISCELL
  mstr_standard offpage *
  page244_i37
#ISCELL
  mstr_standard tap *
  page244_i38
#CELL
  mstr_discrete res *
  page244_i39
#ISCELL
  mstr_standard tap *
  page244_i4
#ISCELL
  mstr_standard tap *
  page244_i40
#CELL
  mstr_discrete cap *
  page244_i41
#ISCELL
  mstr_standard tap *
  page244_i42
#ISCELL
  mstr_standard tap *
  page244_i43
#ISCELL
  mstr_standard tap *
  page244_i44
#ISCELL
  mstr_standard tap *
  page244_i45
#ISCELL
  mstr_standard tap *
  page244_i46
#CELL
  mstr_discrete cap *
  page244_i47
#ISCELL
  mstr_standard tap *
  page244_i48
#ISCELL
  mstr_standard offpage *
  page244_i49
#CELL
  mstr_discrete cap *
  page244_i5
#CELL
  mstr_discrete cap *
  page244_i50
#CELL
  mstr_discrete cap *
  page244_i51
#CELL
  mstr_discrete cap *
  page244_i52
#ISCELL
  mstr_standard tap *
  page244_i53
#ISCELL
  mstr_standard tap *
  page244_i54
#ISCELL
  mstr_standard tap *
  page244_i55
#ISCELL
  mstr_standard offpage *
  page244_i56
#ISCELL
  mstr_standard tap *
  page244_i57
#CELL
  mstr_discrete res *
  page244_i58
#ISCELL
  mstr_standard tap *
  page244_i59
#ISCELL
  mstr_standard tap *
  page244_i6
#ISCELL
  mstr_standard tap *
  page244_i60
#ISCELL
  mstr_standard tap *
  page244_i61
#ISCELL
  mstr_standard tap *
  page244_i62
#ISCELL
  mstr_standard offpage *
  page244_i63
#CELL
  mstr_discrete res *
  page244_i64
#CELL
  mstr_discrete res *
  page244_i65
#CELL
  mstr_discrete res *
  page244_i66
#ISCELL
  mstr_standard tap *
  page244_i67
#ISCELL
  mstr_standard tap *
  page244_i68
#ISCELL
  mstr_standard tap *
  page244_i69
#ISCELL
  mstr_standard tap *
  page244_i7
#ISCELL
  mstr_standard tap *
  page244_i70
#ISCELL
  mstr_standard tap *
  page244_i71
#CELL
  mstr_discrete res *
  page244_i72
#ISCELL
  mstr_standard tap *
  page244_i73
#CELL
  mstr_discrete res *
  page244_i74
#ISCELL
  mstr_standard tap *
  page244_i75
#ISCELL
  mstr_standard tap *
  page244_i76
#CELL
  mstr_discrete res *
  page244_i77
#ISCELL
  mstr_standard tap *
  page244_i78
#ISCELL
  mstr_standard offpage *
  page244_i79
#CELL
  mstr_discrete cap *
  page244_i8
#CELL
  mstr_discrete res *
  page244_i80
#ISCELL
  mstr_standard tap *
  page244_i81
#ISCELL
  mstr_standard tap *
  page244_i82
#ISCELL
  mstr_standard tap *
  page244_i83
#ISCELL
  mstr_standard tap *
  page244_i84
#ISCELL
  mstr_standard tap *
  page244_i85
#CELL
  mstr_discrete res *
  page244_i86
#ISCELL
  mstr_standard tap *
  page244_i87
#ISCELL
  mstr_standard tap *
  page244_i88
#ISCELL
  mstr_standard tap *
  page244_i89
#ISCELL
  mstr_standard offpage *
  page244_i9
#ISCELL
  mstr_standard tap *
  page244_i90
#ISCELL
  mstr_standard tap *
  page244_i91
#ISCELL
  mstr_standard tap *
  page244_i92
#CELL
  mstr_discrete res *
  page244_i93
#CELL
  mstr_discrete res *
  page244_i94
#ISCELL
  mstr_standard tap *
  page244_i95
#ISCELL
  mstr_standard tap *
  page244_i96
#CELL
  mstr_discrete res *
  page244_i97
#CELL
  mstr_discrete res *
  page244_i98
#CELL
  mstr_discrete res *
  page244_i99
